(kicad_pcb
	(version 20260206)
	(generator "pcbnew")
	(generator_version "10.0")
	(general
		(thickness 1.6)
		(legacy_teardrops no)
	)
	(paper "A4")
	(title_block
		(title "03242023_DA0F0TMBIJ0_F0T_Motherboard_J_brd_V01_OCP.brd")
		(comment 1 "Grand Teton / footprints 1953-1959 of 6105")
	)
	(layers
		(0 "F.Cu" signal "TOP")
		(4 "In1.Cu" signal "GND")
		(6 "In2.Cu" signal "IN1")
		(8 "In3.Cu" signal "GND1")
		(10 "In4.Cu" signal "IN2")
		(12 "In5.Cu" signal "GND2")
		(14 "In6.Cu" signal "IN3")
		(16 "In7.Cu" signal "GND3")
		(18 "In8.Cu" signal "VCC")
		(20 "In9.Cu" signal "VCC1")
		(22 "In10.Cu" signal "GND4")
		(24 "In11.Cu" signal "IN4")
		(26 "In12.Cu" signal "GND5")
		(28 "In13.Cu" signal "IN5")
		(30 "In14.Cu" signal "GND6")
		(32 "In15.Cu" signal "IN6")
		(34 "In16.Cu" signal "GND7")
		(2 "B.Cu" signal "BOTTOM")
		(9 "F.Adhes" user "F.Adhesive")
		(11 "B.Adhes" user "B.Adhesive")
		(13 "F.Paste" user "Package Geometry/Pastemask Top")
		(15 "B.Paste" user "Package Geometry/Pastemask Bottom")
		(5 "F.SilkS" user "Ref Des/Silkscreen Top")
		(7 "B.SilkS" user "Ref Des/Silkscreen Bottom")
		(1 "F.Mask" user "Board Geometry/Soldermask Top")
		(3 "B.Mask" user "Board Geometry/Soldermask Bottom")
		(17 "Dwgs.User" user "User.Drawings")
		(19 "Cmts.User" user "User.Comments")
		(21 "Eco1.User" user "User.Eco1")
		(23 "Eco2.User" user "User.Eco2")
		(25 "Edge.Cuts" user "Board Geometry/Outline")
		(27 "Margin" user)
		(31 "F.CrtYd" user "Package Geometry/Place Bound Top")
		(29 "B.CrtYd" user "Package Geometry/Place Bound Bottom")
		(35 "F.Fab" user "Ref Des/Assembly Top")
		(33 "B.Fab" user "Ref Des/Assembly Bottom")
	)
	(footprint ""
		(layer "F.Cu")
		(at 166.351458 -133.77672 90)
		(property "Reference" "C1226"
			(at 0 0 90)
			(layer "F.SilkS")
			(hide yes)
			(effects
				(font
					(size 1.27 1.27)
				)
			)
		)
		(property "Value" ""
			(at 0 0 90)
			(layer "F.Fab")
			(effects
				(font
					(size 1.27 1.27)
				)
			)
		)
		(duplicate_pad_numbers_are_jumpers no)
		(fp_line
			(start 0.7874 -0.4064)
			(end 0.7874 0.4064)
			(stroke
				(width 0.1524)
				(type default)
			)
			(layer "F.SilkS")
		)
		(fp_line
			(start -0.7874 -0.4064)
			(end 0.7874 -0.4064)
			(stroke
				(width 0.1524)
				(type default)
			)
			(layer "F.SilkS")
		)
		(fp_line
			(start 0.7874 0.4064)
			(end -0.7874 0.4064)
			(stroke
				(width 0.1524)
				(type default)
			)
			(layer "F.SilkS")
		)
		(fp_line
			(start -0.7874 0.4064)
			(end -0.7874 -0.4064)
			(stroke
				(width 0.1524)
				(type default)
			)
			(layer "F.SilkS")
		)
		(fp_line
			(start -0.12065 -0.305054)
			(end -0.12065 -0.2794)
			(stroke
				(width 0.1)
				(type default)
			)
			(layer "F.Fab")
		)
		(fp_line
			(start -0.67945 -0.305054)
			(end -0.12065 -0.305054)
			(stroke
				(width 0.1)
				(type default)
			)
			(layer "F.Fab")
		)
		(fp_line
			(start 0.67945 -0.3048)
			(end 0.67945 0.3048)
			(stroke
				(width 0.1)
				(type default)
			)
			(layer "F.Fab")
		)
		(fp_line
			(start 0.12065 -0.3048)
			(end 0.67945 -0.3048)
			(stroke
				(width 0.1)
				(type default)
			)
			(layer "F.Fab")
		)
		(fp_line
			(start 0.12065 -0.2794)
			(end 0.12065 -0.3048)
			(stroke
				(width 0.1)
				(type default)
			)
			(layer "F.Fab")
		)
		(fp_line
			(start -0.12065 -0.2794)
			(end 0.12065 -0.2794)
			(stroke
				(width 0.1)
				(type default)
			)
			(layer "F.Fab")
		)
		(fp_line
			(start 0.120396 0.2794)
			(end -0.12065 0.2794)
			(stroke
				(width 0.1)
				(type default)
			)
			(layer "F.Fab")
		)
		(fp_line
			(start -0.12065 0.2794)
			(end -0.12065 0.3048)
			(stroke
				(width 0.1)
				(type default)
			)
			(layer "F.Fab")
		)
		(fp_line
			(start 0.67945 0.3048)
			(end 0.120396 0.3048)
			(stroke
				(width 0.1)
				(type default)
			)
			(layer "F.Fab")
		)
		(fp_line
			(start 0.120396 0.3048)
			(end 0.120396 0.2794)
			(stroke
				(width 0.1)
				(type default)
			)
			(layer "F.Fab")
		)
		(fp_line
			(start -0.12065 0.3048)
			(end -0.67945 0.3048)
			(stroke
				(width 0.1)
				(type default)
			)
			(layer "F.Fab")
		)
		(fp_line
			(start -0.67945 0.3048)
			(end -0.67945 -0.305054)
			(stroke
				(width 0.1)
				(type default)
			)
			(layer "F.Fab")
		)
		(pad "1" smd circle
			(at -0.40005 0 90)
			(size 0 0)
			(layers "F.Cu" "F.Mask" "F.Paste")
			(net "VR_P5V_EN_D_R")
		)
		(pad "2" smd circle
			(at 0.40005 0 90)
			(size 0 0)
			(layers "F.Cu" "F.Mask" "F.Paste")
			(net "GND")
		)
	)
	(footprint ""
		(layer "F.Cu")
		(at 178.816 -19.776948 90)
		(property "Reference" "R1387"
			(at 0 0 90)
			(layer "F.SilkS")
			(hide yes)
			(effects
				(font
					(size 1.27 1.27)
				)
			)
		)
		(property "Value" ""
			(at 0 0 90)
			(layer "F.Fab")
			(effects
				(font
					(size 1.27 1.27)
				)
			)
		)
		(duplicate_pad_numbers_are_jumpers no)
		(fp_line
			(start 0.7874 -0.4064)
			(end 0.7874 0.4064)
			(stroke
				(width 0.1524)
				(type default)
			)
			(layer "F.SilkS")
		)
		(fp_line
			(start -0.7874 -0.4064)
			(end 0.7874 -0.4064)
			(stroke
				(width 0.1524)
				(type default)
			)
			(layer "F.SilkS")
		)
		(fp_line
			(start 0.7874 0.4064)
			(end -0.7874 0.4064)
			(stroke
				(width 0.1524)
				(type default)
			)
			(layer "F.SilkS")
		)
		(fp_line
			(start -0.7874 0.4064)
			(end -0.7874 -0.4064)
			(stroke
				(width 0.1524)
				(type default)
			)
			(layer "F.SilkS")
		)
		(fp_line
			(start -0.12065 -0.305054)
			(end -0.12065 -0.2794)
			(stroke
				(width 0.1)
				(type default)
			)
			(layer "F.Fab")
		)
		(fp_line
			(start -0.67945 -0.305054)
			(end -0.12065 -0.305054)
			(stroke
				(width 0.1)
				(type default)
			)
			(layer "F.Fab")
		)
		(fp_line
			(start 0.67945 -0.3048)
			(end 0.67945 0.3048)
			(stroke
				(width 0.1)
				(type default)
			)
			(layer "F.Fab")
		)
		(fp_line
			(start 0.12065 -0.3048)
			(end 0.67945 -0.3048)
			(stroke
				(width 0.1)
				(type default)
			)
			(layer "F.Fab")
		)
		(fp_line
			(start 0.12065 -0.2794)
			(end 0.12065 -0.3048)
			(stroke
				(width 0.1)
				(type default)
			)
			(layer "F.Fab")
		)
		(fp_line
			(start -0.12065 -0.2794)
			(end 0.12065 -0.2794)
			(stroke
				(width 0.1)
				(type default)
			)
			(layer "F.Fab")
		)
		(fp_line
			(start 0.120396 0.2794)
			(end -0.12065 0.2794)
			(stroke
				(width 0.1)
				(type default)
			)
			(layer "F.Fab")
		)
		(fp_line
			(start -0.12065 0.2794)
			(end -0.12065 0.3048)
			(stroke
				(width 0.1)
				(type default)
			)
			(layer "F.Fab")
		)
		(fp_line
			(start 0.67945 0.3048)
			(end 0.120396 0.3048)
			(stroke
				(width 0.1)
				(type default)
			)
			(layer "F.Fab")
		)
		(fp_line
			(start 0.120396 0.3048)
			(end 0.120396 0.2794)
			(stroke
				(width 0.1)
				(type default)
			)
			(layer "F.Fab")
		)
		(fp_line
			(start -0.12065 0.3048)
			(end -0.67945 0.3048)
			(stroke
				(width 0.1)
				(type default)
			)
			(layer "F.Fab")
		)
		(fp_line
			(start -0.67945 0.3048)
			(end -0.67945 -0.305054)
			(stroke
				(width 0.1)
				(type default)
			)
			(layer "F.Fab")
		)
		(pad "1" smd circle
			(at -0.40005 0 90)
			(size 0 0)
			(layers "F.Cu" "F.Mask" "F.Paste")
			(net "SMB_SML1_PMBUS_3V3AUX_PCH_SDA")
		)
		(pad "2" smd circle
			(at 0.40005 0 90)
			(size 0 0)
			(layers "F.Cu" "F.Mask" "F.Paste")
			(net "P3V3_AUX")
		)
	)
	(footprint ""
		(layer "F.Cu")
		(at 74.720958 -408.517344 -90)
		(property "Reference" "C693"
			(at 0 0 270)
			(layer "F.SilkS")
			(hide yes)
			(effects
				(font
					(size 1.27 1.27)
				)
			)
		)
		(property "Value" ""
			(at 0 0 270)
			(layer "F.Fab")
			(effects
				(font
					(size 1.27 1.27)
				)
			)
		)
		(duplicate_pad_numbers_are_jumpers no)
		(fp_line
			(start -0.299974 0.150114)
			(end -0.299974 -0.150114)
			(stroke
				(width 0.1)
				(type default)
			)
			(layer "F.Fab")
		)
		(fp_line
			(start 0.299974 0.150114)
			(end -0.299974 0.150114)
			(stroke
				(width 0.1)
				(type default)
			)
			(layer "F.Fab")
		)
		(fp_line
			(start -0.299974 -0.150114)
			(end 0.299974 -0.150114)
			(stroke
				(width 0.1)
				(type default)
			)
			(layer "F.Fab")
		)
		(fp_line
			(start 0.299974 -0.150114)
			(end 0.299974 0.150114)
			(stroke
				(width 0.1)
				(type default)
			)
			(layer "F.Fab")
		)
		(pad "1" smd rect
			(at -0.2667 0 270)
			(size 0.3048 0.381)
			(layers "F.Cu" "F.Mask" "F.Paste")
			(net "P5E_CPU1_PE4_TX_C_DP<8>")
		)
		(pad "2" smd rect
			(at 0.2667 0 270)
			(size 0.3048 0.381)
			(layers "F.Cu" "F.Mask" "F.Paste")
			(net "P5E_CPU1_PE4_TX_DP<8>")
		)
	)
	(footprint ""
		(layer "F.Cu")
		(at 320.190622 -56.251348)
		(property "Reference" "R611"
			(at 0 0 0)
			(layer "F.SilkS")
			(hide yes)
			(effects
				(font
					(size 1.27 1.27)
				)
			)
		)
		(property "Value" ""
			(at 0 0 0)
			(layer "F.Fab")
			(effects
				(font
					(size 1.27 1.27)
				)
			)
		)
		(duplicate_pad_numbers_are_jumpers no)
		(fp_line
			(start -0.7874 -0.4064)
			(end 0.7874 -0.4064)
			(stroke
				(width 0.1524)
				(type default)
			)
			(layer "F.SilkS")
		)
		(fp_line
			(start -0.7874 0.4064)
			(end -0.7874 -0.4064)
			(stroke
				(width 0.1524)
				(type default)
			)
			(layer "F.SilkS")
		)
		(fp_line
			(start 0.7874 -0.4064)
			(end 0.7874 0.4064)
			(stroke
				(width 0.1524)
				(type default)
			)
			(layer "F.SilkS")
		)
		(fp_line
			(start 0.7874 0.4064)
			(end -0.7874 0.4064)
			(stroke
				(width 0.1524)
				(type default)
			)
			(layer "F.SilkS")
		)
		(fp_line
			(start -0.67945 -0.305054)
			(end -0.12065 -0.305054)
			(stroke
				(width 0.1)
				(type default)
			)
			(layer "F.Fab")
		)
		(fp_line
			(start -0.67945 0.3048)
			(end -0.67945 -0.305054)
			(stroke
				(width 0.1)
				(type default)
			)
			(layer "F.Fab")
		)
		(fp_line
			(start -0.12065 -0.305054)
			(end -0.12065 -0.2794)
			(stroke
				(width 0.1)
				(type default)
			)
			(layer "F.Fab")
		)
		(fp_line
			(start -0.12065 -0.2794)
			(end 0.12065 -0.2794)
			(stroke
				(width 0.1)
				(type default)
			)
			(layer "F.Fab")
		)
		(fp_line
			(start -0.12065 0.2794)
			(end -0.12065 0.3048)
			(stroke
				(width 0.1)
				(type default)
			)
			(layer "F.Fab")
		)
		(fp_line
			(start -0.12065 0.3048)
			(end -0.67945 0.3048)
			(stroke
				(width 0.1)
				(type default)
			)
			(layer "F.Fab")
		)
		(fp_line
			(start 0.120396 0.2794)
			(end -0.12065 0.2794)
			(stroke
				(width 0.1)
				(type default)
			)
			(layer "F.Fab")
		)
		(fp_line
			(start 0.120396 0.3048)
			(end 0.120396 0.2794)
			(stroke
				(width 0.1)
				(type default)
			)
			(layer "F.Fab")
		)
		(fp_line
			(start 0.12065 -0.3048)
			(end 0.67945 -0.3048)
			(stroke
				(width 0.1)
				(type default)
			)
			(layer "F.Fab")
		)
		(fp_line
			(start 0.12065 -0.2794)
			(end 0.12065 -0.3048)
			(stroke
				(width 0.1)
				(type default)
			)
			(layer "F.Fab")
		)
		(fp_line
			(start 0.67945 -0.3048)
			(end 0.67945 0.3048)
			(stroke
				(width 0.1)
				(type default)
			)
			(layer "F.Fab")
		)
		(fp_line
			(start 0.67945 0.3048)
			(end 0.120396 0.3048)
			(stroke
				(width 0.1)
				(type default)
			)
			(layer "F.Fab")
		)
		(pad "1" smd circle
			(at -0.40005 0)
			(size 0 0)
			(layers "F.Cu" "F.Mask" "F.Paste")
			(net "P3V3_AUX")
		)
		(pad "2" smd circle
			(at 0.40005 0)
			(size 0 0)
			(layers "F.Cu" "F.Mask" "F.Paste")
			(net "FM_PCH_EXTERNALCLKMODE")
		)
	)
	(footprint ""
		(layer "F.Cu")
		(at 210.560412 -100.908104)
		(property "Reference" "R2233"
			(at 0 0 0)
			(layer "F.SilkS")
			(hide yes)
			(effects
				(font
					(size 1.27 1.27)
				)
			)
		)
		(property "Value" ""
			(at 0 0 0)
			(layer "F.Fab")
			(effects
				(font
					(size 1.27 1.27)
				)
			)
		)
		(duplicate_pad_numbers_are_jumpers no)
		(fp_line
			(start -0.7874 -0.4064)
			(end 0.7874 -0.4064)
			(stroke
				(width 0.1524)
				(type default)
			)
			(layer "F.SilkS")
		)
		(fp_line
			(start -0.7874 0.4064)
			(end -0.7874 -0.4064)
			(stroke
				(width 0.1524)
				(type default)
			)
			(layer "F.SilkS")
		)
		(fp_line
			(start 0.7874 -0.4064)
			(end 0.7874 0.4064)
			(stroke
				(width 0.1524)
				(type default)
			)
			(layer "F.SilkS")
		)
		(fp_line
			(start 0.7874 0.4064)
			(end -0.7874 0.4064)
			(stroke
				(width 0.1524)
				(type default)
			)
			(layer "F.SilkS")
		)
		(fp_line
			(start -0.67945 -0.305054)
			(end -0.12065 -0.305054)
			(stroke
				(width 0.1)
				(type default)
			)
			(layer "F.Fab")
		)
		(fp_line
			(start -0.67945 0.3048)
			(end -0.67945 -0.305054)
			(stroke
				(width 0.1)
				(type default)
			)
			(layer "F.Fab")
		)
		(fp_line
			(start -0.12065 -0.305054)
			(end -0.12065 -0.2794)
			(stroke
				(width 0.1)
				(type default)
			)
			(layer "F.Fab")
		)
		(fp_line
			(start -0.12065 -0.2794)
			(end 0.12065 -0.2794)
			(stroke
				(width 0.1)
				(type default)
			)
			(layer "F.Fab")
		)
		(fp_line
			(start -0.12065 0.2794)
			(end -0.12065 0.3048)
			(stroke
				(width 0.1)
				(type default)
			)
			(layer "F.Fab")
		)
		(fp_line
			(start -0.12065 0.3048)
			(end -0.67945 0.3048)
			(stroke
				(width 0.1)
				(type default)
			)
			(layer "F.Fab")
		)
		(fp_line
			(start 0.120396 0.2794)
			(end -0.12065 0.2794)
			(stroke
				(width 0.1)
				(type default)
			)
			(layer "F.Fab")
		)
		(fp_line
			(start 0.120396 0.3048)
			(end 0.120396 0.2794)
			(stroke
				(width 0.1)
				(type default)
			)
			(layer "F.Fab")
		)
		(fp_line
			(start 0.12065 -0.3048)
			(end 0.67945 -0.3048)
			(stroke
				(width 0.1)
				(type default)
			)
			(layer "F.Fab")
		)
		(fp_line
			(start 0.12065 -0.2794)
			(end 0.12065 -0.3048)
			(stroke
				(width 0.1)
				(type default)
			)
			(layer "F.Fab")
		)
		(fp_line
			(start 0.67945 -0.3048)
			(end 0.67945 0.3048)
			(stroke
				(width 0.1)
				(type default)
			)
			(layer "F.Fab")
		)
		(fp_line
			(start 0.67945 0.3048)
			(end 0.120396 0.3048)
			(stroke
				(width 0.1)
				(type default)
			)
			(layer "F.Fab")
		)
		(pad "1" smd circle
			(at -0.40005 0)
			(size 0 0)
			(layers "F.Cu" "F.Mask" "F.Paste")
			(net "P3V3_AUX")
		)
		(pad "2" smd circle
			(at 0.40005 0)
			(size 0 0)
			(layers "F.Cu" "F.Mask" "F.Paste")
			(net "FM_UV_ADR_TRIGGER_N")
		)
	)
	(footprint ""
		(layer "F.Cu")
		(at 353.254818 -244.03177 90)
		(property "Reference" "C999"
			(at 0 0 90)
			(layer "F.SilkS")
			(hide yes)
			(effects
				(font
					(size 1.27 1.27)
				)
			)
		)
		(property "Value" ""
			(at 0 0 90)
			(layer "F.Fab")
			(effects
				(font
					(size 1.27 1.27)
				)
			)
		)
		(duplicate_pad_numbers_are_jumpers no)
		(fp_line
			(start 0.7874 -0.4064)
			(end 0.7874 0.4064)
			(stroke
				(width 0.1524)
				(type default)
			)
			(layer "F.SilkS")
		)
		(fp_line
			(start -0.7874 -0.4064)
			(end 0.7874 -0.4064)
			(stroke
				(width 0.1524)
				(type default)
			)
			(layer "F.SilkS")
		)
		(fp_line
			(start 0.7874 0.4064)
			(end -0.7874 0.4064)
			(stroke
				(width 0.1524)
				(type default)
			)
			(layer "F.SilkS")
		)
		(fp_line
			(start -0.7874 0.4064)
			(end -0.7874 -0.4064)
			(stroke
				(width 0.1524)
				(type default)
			)
			(layer "F.SilkS")
		)
		(fp_line
			(start -0.12065 -0.305054)
			(end -0.12065 -0.2794)
			(stroke
				(width 0.1)
				(type default)
			)
			(layer "F.Fab")
		)
		(fp_line
			(start -0.67945 -0.305054)
			(end -0.12065 -0.305054)
			(stroke
				(width 0.1)
				(type default)
			)
			(layer "F.Fab")
		)
		(fp_line
			(start 0.67945 -0.3048)
			(end 0.67945 0.3048)
			(stroke
				(width 0.1)
				(type default)
			)
			(layer "F.Fab")
		)
		(fp_line
			(start 0.12065 -0.3048)
			(end 0.67945 -0.3048)
			(stroke
				(width 0.1)
				(type default)
			)
			(layer "F.Fab")
		)
		(fp_line
			(start 0.12065 -0.2794)
			(end 0.12065 -0.3048)
			(stroke
				(width 0.1)
				(type default)
			)
			(layer "F.Fab")
		)
		(fp_line
			(start -0.12065 -0.2794)
			(end 0.12065 -0.2794)
			(stroke
				(width 0.1)
				(type default)
			)
			(layer "F.Fab")
		)
		(fp_line
			(start 0.120396 0.2794)
			(end -0.12065 0.2794)
			(stroke
				(width 0.1)
				(type default)
			)
			(layer "F.Fab")
		)
		(fp_line
			(start -0.12065 0.2794)
			(end -0.12065 0.3048)
			(stroke
				(width 0.1)
				(type default)
			)
			(layer "F.Fab")
		)
		(fp_line
			(start 0.67945 0.3048)
			(end 0.120396 0.3048)
			(stroke
				(width 0.1)
				(type default)
			)
			(layer "F.Fab")
		)
		(fp_line
			(start 0.120396 0.3048)
			(end 0.120396 0.2794)
			(stroke
				(width 0.1)
				(type default)
			)
			(layer "F.Fab")
		)
		(fp_line
			(start -0.12065 0.3048)
			(end -0.67945 0.3048)
			(stroke
				(width 0.1)
				(type default)
			)
			(layer "F.Fab")
		)
		(fp_line
			(start -0.67945 0.3048)
			(end -0.67945 -0.305054)
			(stroke
				(width 0.1)
				(type default)
			)
			(layer "F.Fab")
		)
		(pad "1" smd circle
			(at -0.40005 0 90)
			(size 0 0)
			(layers "F.Cu" "F.Mask" "F.Paste")
			(net "PVCCIN_CPU0")
		)
		(pad "2" smd circle
			(at 0.40005 0 90)
			(size 0 0)
			(layers "F.Cu" "F.Mask" "F.Paste")
			(net "GND")
		)
	)
	(footprint ""
		(layer "F.Cu")
		(at 102.306374 -409.57754 90)
		(property "Reference" "C2075"
			(at 0 0 90)
			(layer "F.SilkS")
			(hide yes)
			(effects
				(font
					(size 1.27 1.27)
				)
			)
		)
		(property "Value" ""
			(at 0 0 90)
			(layer "F.Fab")
			(effects
				(font
					(size 1.27 1.27)
				)
			)
		)
		(duplicate_pad_numbers_are_jumpers no)
		(fp_line
			(start 0.299974 -0.150114)
			(end 0.299974 0.150114)
			(stroke
				(width 0.1)
				(type default)
			)
			(layer "F.Fab")
		)
		(fp_line
			(start -0.299974 -0.150114)
			(end 0.299974 -0.150114)
			(stroke
				(width 0.1)
				(type default)
			)
			(layer "F.Fab")
		)
		(fp_line
			(start 0.299974 0.150114)
			(end -0.299974 0.150114)
			(stroke
				(width 0.1)
				(type default)
			)
			(layer "F.Fab")
		)
		(fp_line
			(start -0.299974 0.150114)
			(end -0.299974 -0.150114)
			(stroke
				(width 0.1)
				(type default)
			)
			(layer "F.Fab")
		)
		(pad "1" smd rect
			(at -0.2667 0 90)
			(size 0.3048 0.381)
			(layers "F.Cu" "F.Mask" "F.Paste")
			(net "P3E_PCH_NVS_TX_DP<0>")
		)
		(pad "2" smd rect
			(at 0.2667 0 90)
			(size 0.3048 0.381)
			(layers "F.Cu" "F.Mask" "F.Paste")
			(net "P3E_PCH_NVS_TX_C_DP<0>")
		)
		(zone
			(layer "In1.Cu")
			(hatch none 0.5)
			(connect_pads
				(clearance 0)
			)
			(min_thickness 0.25)
			(keepout
				(tracks not_allowed)
				(vias allowed)
				(pads allowed)
				(copperpour not_allowed)
				(footprints allowed)
			)
			(placement
				(enabled no)
				(sheetname "")
			)
			(fill
				(thermal_gap 0.5)
				(thermal_bridge_width 0.5)
				(island_removal_mode 0)
			)
			(polygon
				(pts
					(arc
						(start 102.547674 -409.71724)
						(mid 102.525356 -409.663358)
						(end 102.471474 -409.64104)
					)
					(arc
						(start 102.141274 -409.64104)
						(mid 102.087392 -409.663358)
						(end 102.065074 -409.71724)
					)
					(arc
						(start 102.065074 -409.97124)
						(mid 102.087392 -410.025122)
						(end 102.141274 -410.04744)
					)
					(arc
						(start 102.471474 -410.04744)
						(mid 102.525356 -410.025122)
						(end 102.547674 -409.97124)
					)
				)
			)
		)
		(zone
			(layer "In1.Cu")
			(hatch none 0.5)
			(connect_pads
				(clearance 0)
			)
			(min_thickness 0.25)
			(keepout
				(tracks not_allowed)
				(vias allowed)
				(pads allowed)
				(copperpour not_allowed)
				(footprints allowed)
			)
			(placement
				(enabled no)
				(sheetname "")
			)
			(fill
				(thermal_gap 0.5)
				(thermal_bridge_width 0.5)
				(island_removal_mode 0)
			)
			(polygon
				(pts
					(arc
						(start 102.547674 -409.18384)
						(mid 102.525356 -409.129958)
						(end 102.471474 -409.10764)
					)
					(arc
						(start 102.141274 -409.10764)
						(mid 102.087392 -409.129958)
						(end 102.065074 -409.18384)
					)
					(arc
						(start 102.065074 -409.43784)
						(mid 102.087392 -409.491722)
						(end 102.141274 -409.51404)
					)
					(arc
						(start 102.471474 -409.51404)
						(mid 102.525356 -409.491722)
						(end 102.547674 -409.43784)
					)
				)
			)
		)
	)
)
